# S9S_MB_2U (Grand Teton) — schematic netlist excerpt (pin names and nets, part order shuffled) for the footprints in the layout excerpt that follows; sources: Cadence DE-HDL packaged netlist, KiCad conversion of 03242023_DA0F0TMBIJ0_F0T_Motherboard_J_brd_V01_OCP.brd

R611  Q_RES  1K 1% CHIP  pkg 0402LF  page 199 : A = P3V3_AUX ; B = FM_PCH_EXTERNALCLKMODE
R2233  Q_RES  10K 1% CHIP  pkg 0402LF  page 306 : A = P3V3_AUX ; B = FM_UV_ADR_TRIGGER_N

(kicad_pcb
	(version 20260206)
	(generator "pcbnew")
	(generator_version "10.0")
	(general
		(thickness 1.6)
		(legacy_teardrops no)
	)
	(paper "A4")
	(title_block
		(title "03242023_DA0F0TMBIJ0_F0T_Motherboard_J_brd_V01_OCP.brd")
		(comment 1 "Grand Teton / footprints 1956-1957 of 6105")
	)
	(layers
		(0 "F.Cu" signal "TOP")
		(4 "In1.Cu" signal "GND")
		(6 "In2.Cu" signal "IN1")
		(8 "In3.Cu" signal "GND1")
		(10 "In4.Cu" signal "IN2")
		(12 "In5.Cu" signal "GND2")
		(14 "In6.Cu" signal "IN3")
		(16 "In7.Cu" signal "GND3")
		(18 "In8.Cu" signal "VCC")
		(20 "In9.Cu" signal "VCC1")
		(22 "In10.Cu" signal "GND4")
		(24 "In11.Cu" signal "IN4")
		(26 "In12.Cu" signal "GND5")
		(28 "In13.Cu" signal "IN5")
		(30 "In14.Cu" signal "GND6")
		(32 "In15.Cu" signal "IN6")
		(34 "In16.Cu" signal "GND7")
		(2 "B.Cu" signal "BOTTOM")
		(9 "F.Adhes" user "F.Adhesive")
		(11 "B.Adhes" user "B.Adhesive")
		(13 "F.Paste" user "Package Geometry/Pastemask Top")
		(15 "B.Paste" user "Package Geometry/Pastemask Bottom")
		(5 "F.SilkS" user "Ref Des/Silkscreen Top")
		(7 "B.SilkS" user "Ref Des/Silkscreen Bottom")
		(1 "F.Mask" user "Board Geometry/Soldermask Top")
		(3 "B.Mask" user "Board Geometry/Soldermask Bottom")
		(17 "Dwgs.User" user "User.Drawings")
		(19 "Cmts.User" user "User.Comments")
		(21 "Eco1.User" user "User.Eco1")
		(23 "Eco2.User" user "User.Eco2")
		(25 "Edge.Cuts" user "Board Geometry/Outline")
		(27 "Margin" user)
		(31 "F.CrtYd" user "Package Geometry/Place Bound Top")
		(29 "B.CrtYd" user "Package Geometry/Place Bound Bottom")
		(35 "F.Fab" user "Ref Des/Assembly Top")
		(33 "B.Fab" user "Ref Des/Assembly Bottom")
	)
	(footprint ""
		(layer "F.Cu")
		(at 320.190622 -56.251348)
		(property "Reference" "R611"
			(at 0 0 0)
			(layer "F.SilkS")
			(hide yes)
			(effects
				(font
					(size 1.27 1.27)
				)
			)
		)
		(property "Value" ""
			(at 0 0 0)
			(layer "F.Fab")
			(effects
				(font
					(size 1.27 1.27)
				)
			)
		)
		(duplicate_pad_numbers_are_jumpers no)
		(fp_line
			(start -0.7874 -0.4064)
			(end 0.7874 -0.4064)
			(stroke
				(width 0.1524)
				(type default)
			)
			(layer "F.SilkS")
		)
		(fp_line
			(start -0.7874 0.4064)
			(end -0.7874 -0.4064)
			(stroke
				(width 0.1524)
				(type default)
			)
			(layer "F.SilkS")
		)
		(fp_line
			(start 0.7874 -0.4064)
			(end 0.7874 0.4064)
			(stroke
				(width 0.1524)
				(type default)
			)
			(layer "F.SilkS")
		)
		(fp_line
			(start 0.7874 0.4064)
			(end -0.7874 0.4064)
			(stroke
				(width 0.1524)
				(type default)
			)
			(layer "F.SilkS")
		)
		(fp_line
			(start -0.67945 -0.305054)
			(end -0.12065 -0.305054)
			(stroke
				(width 0.1)
				(type default)
			)
			(layer "F.Fab")
		)
		(fp_line
			(start -0.67945 0.3048)
			(end -0.67945 -0.305054)
			(stroke
				(width 0.1)
				(type default)
			)
			(layer "F.Fab")
		)
		(fp_line
			(start -0.12065 -0.305054)
			(end -0.12065 -0.2794)
			(stroke
				(width 0.1)
				(type default)
			)
			(layer "F.Fab")
		)
		(fp_line
			(start -0.12065 -0.2794)
			(end 0.12065 -0.2794)
			(stroke
				(width 0.1)
				(type default)
			)
			(layer "F.Fab")
		)
		(fp_line
			(start -0.12065 0.2794)
			(end -0.12065 0.3048)
			(stroke
				(width 0.1)
				(type default)
			)
			(layer "F.Fab")
		)
		(fp_line
			(start -0.12065 0.3048)
			(end -0.67945 0.3048)
			(stroke
				(width 0.1)
				(type default)
			)
			(layer "F.Fab")
		)
		(fp_line
			(start 0.120396 0.2794)
			(end -0.12065 0.2794)
			(stroke
				(width 0.1)
				(type default)
			)
			(layer "F.Fab")
		)
		(fp_line
			(start 0.120396 0.3048)
			(end 0.120396 0.2794)
			(stroke
				(width 0.1)
				(type default)
			)
			(layer "F.Fab")
		)
		(fp_line
			(start 0.12065 -0.3048)
			(end 0.67945 -0.3048)
			(stroke
				(width 0.1)
				(type default)
			)
			(layer "F.Fab")
		)
		(fp_line
			(start 0.12065 -0.2794)
			(end 0.12065 -0.3048)
			(stroke
				(width 0.1)
				(type default)
			)
			(layer "F.Fab")
		)
		(fp_line
			(start 0.67945 -0.3048)
			(end 0.67945 0.3048)
			(stroke
				(width 0.1)
				(type default)
			)
			(layer "F.Fab")
		)
		(fp_line
			(start 0.67945 0.3048)
			(end 0.120396 0.3048)
			(stroke
				(width 0.1)
				(type default)
			)
			(layer "F.Fab")
		)
		(pad "1" smd circle
			(at -0.40005 0)
			(size 0 0)
			(layers "F.Cu" "F.Mask" "F.Paste")
			(net "P3V3_AUX")
		)
		(pad "2" smd circle
			(at 0.40005 0)
			(size 0 0)
			(layers "F.Cu" "F.Mask" "F.Paste")
			(net "FM_PCH_EXTERNALCLKMODE")
		)
	)
	(footprint ""
		(layer "F.Cu")
		(at 210.560412 -100.908104)
		(property "Reference" "R2233"
			(at 0 0 0)
			(layer "F.SilkS")
			(hide yes)
			(effects
				(font
					(size 1.27 1.27)
				)
			)
		)
		(property "Value" ""
			(at 0 0 0)
			(layer "F.Fab")
			(effects
				(font
					(size 1.27 1.27)
				)
			)
		)
		(duplicate_pad_numbers_are_jumpers no)
		(fp_line
			(start -0.7874 -0.4064)
			(end 0.7874 -0.4064)
			(stroke
				(width 0.1524)
				(type default)
			)
			(layer "F.SilkS")
		)
		(fp_line
			(start -0.7874 0.4064)
			(end -0.7874 -0.4064)
			(stroke
				(width 0.1524)
				(type default)
			)
			(layer "F.SilkS")
		)
		(fp_line
			(start 0.7874 -0.4064)
			(end 0.7874 0.4064)
			(stroke
				(width 0.1524)
				(type default)
			)
			(layer "F.SilkS")
		)
		(fp_line
			(start 0.7874 0.4064)
			(end -0.7874 0.4064)
			(stroke
				(width 0.1524)
				(type default)
			)
			(layer "F.SilkS")
		)
		(fp_line
			(start -0.67945 -0.305054)
			(end -0.12065 -0.305054)
			(stroke
				(width 0.1)
				(type default)
			)
			(layer "F.Fab")
		)
		(fp_line
			(start -0.67945 0.3048)
			(end -0.67945 -0.305054)
			(stroke
				(width 0.1)
				(type default)
			)
			(layer "F.Fab")
		)
		(fp_line
			(start -0.12065 -0.305054)
			(end -0.12065 -0.2794)
			(stroke
				(width 0.1)
				(type default)
			)
			(layer "F.Fab")
		)
		(fp_line
			(start -0.12065 -0.2794)
			(end 0.12065 -0.2794)
			(stroke
				(width 0.1)
				(type default)
			)
			(layer "F.Fab")
		)
		(fp_line
			(start -0.12065 0.2794)
			(end -0.12065 0.3048)
			(stroke
				(width 0.1)
				(type default)
			)
			(layer "F.Fab")
		)
		(fp_line
			(start -0.12065 0.3048)
			(end -0.67945 0.3048)
			(stroke
				(width 0.1)
				(type default)
			)
			(layer "F.Fab")
		)
		(fp_line
			(start 0.120396 0.2794)
			(end -0.12065 0.2794)
			(stroke
				(width 0.1)
				(type default)
			)
			(layer "F.Fab")
		)
		(fp_line
			(start 0.120396 0.3048)
			(end 0.120396 0.2794)
			(stroke
				(width 0.1)
				(type default)
			)
			(layer "F.Fab")
		)
		(fp_line
			(start 0.12065 -0.3048)
			(end 0.67945 -0.3048)
			(stroke
				(width 0.1)
				(type default)
			)
			(layer "F.Fab")
		)
		(fp_line
			(start 0.12065 -0.2794)
			(end 0.12065 -0.3048)
			(stroke
				(width 0.1)
				(type default)
			)
			(layer "F.Fab")
		)
		(fp_line
			(start 0.67945 -0.3048)
			(end 0.67945 0.3048)
			(stroke
				(width 0.1)
				(type default)
			)
			(layer "F.Fab")
		)
		(fp_line
			(start 0.67945 0.3048)
			(end 0.120396 0.3048)
			(stroke
				(width 0.1)
				(type default)
			)
			(layer "F.Fab")
		)
		(pad "1" smd circle
			(at -0.40005 0)
			(size 0 0)
			(layers "F.Cu" "F.Mask" "F.Paste")
			(net "P3V3_AUX")
		)
		(pad "2" smd circle
			(at 0.40005 0)
			(size 0 0)
			(layers "F.Cu" "F.Mask" "F.Paste")
			(net "FM_UV_ADR_TRIGGER_N")
		)
	)
)
